# T6G (Grand Teton) — schematic netlist excerpt (pin names and nets, part order shuffled) for the footprints in the layout excerpt that follows; sources: Cadence DE-HDL packaged netlist, KiCad conversion of 04192023_DAF0TMB3IC0_F0TG_MB_C_brd_V02_OCP.brd

R4065  Q_RES  10K 1% CHIP  pkg 0402LF  page 140 : A = P12V_AUX ; B = P12V_OCP_2_EN_G
C6714  Q_CAP_DIFFBUS  DIFF BUS_0.22UF 6.3V 20% X6S  pkg C0201  page 341 : \1\ = P5E_CPU1_P2_TX_BUF_C_DN<10> ; \2\ = P5E_CPU1_P2_TX_BUF_DN<10>
R8180  Q_RES  1K 1% CHIP  pkg 0402LF  page 210 : A = PVDD18_S5_P1 ; B = PVDDCR_CPU0_P1_OCP_N_R

(kicad_pcb
	(version 20260206)
	(generator "pcbnew")
	(generator_version "10.0")
	(general
		(thickness 1.6)
		(legacy_teardrops no)
	)
	(paper "A4")
	(title_block
		(title "04192023_DAF0TMB3IC0_F0TG_MB_C_brd_V02_OCP.brd")
		(comment 1 "Grand Teton / footprints 4826-4828 of 8354")
	)
	(layers
		(0 "F.Cu" signal "TOP")
		(4 "In1.Cu" signal "GND")
		(6 "In2.Cu" signal "IN1")
		(8 "In3.Cu" signal "GND1")
		(10 "In4.Cu" signal "IN2")
		(12 "In5.Cu" signal "GND2")
		(14 "In6.Cu" signal "IN3")
		(16 "In7.Cu" signal "GND3")
		(18 "In8.Cu" signal "VCC")
		(20 "In9.Cu" signal "VCC1")
		(22 "In10.Cu" signal "GND4")
		(24 "In11.Cu" signal "IN4")
		(26 "In12.Cu" signal "GND5")
		(28 "In13.Cu" signal "IN5")
		(30 "In14.Cu" signal "GND6")
		(32 "In15.Cu" signal "IN6")
		(34 "In16.Cu" signal "GND7")
		(2 "B.Cu" signal "BOTTOM")
		(9 "F.Adhes" user "F.Adhesive")
		(11 "B.Adhes" user "B.Adhesive")
		(13 "F.Paste" user "Package Geometry/Pastemask Top")
		(15 "B.Paste" user "Package Geometry/Pastemask Bottom")
		(5 "F.SilkS" user "Ref Des/Silkscreen Top")
		(7 "B.SilkS" user "Ref Des/Silkscreen Bottom")
		(1 "F.Mask" user "Board Geometry/Soldermask Top")
		(3 "B.Mask" user "Board Geometry/Soldermask Bottom")
		(17 "Dwgs.User" user "User.Drawings")
		(19 "Cmts.User" user "User.Comments")
		(21 "Eco1.User" user "User.Eco1")
		(23 "Eco2.User" user "User.Eco2")
		(25 "Edge.Cuts" user "Board Geometry/Outline")
		(27 "Margin" user)
		(31 "F.CrtYd" user "Package Geometry/Place Bound Top")
		(29 "B.CrtYd" user "Package Geometry/Place Bound Bottom")
		(35 "F.Fab" user "Ref Des/Assembly Top")
		(33 "B.Fab" user "Ref Des/Assembly Bottom")
	)
	(footprint ""
		(layer "F.Cu")
		(at 59.8678 -36.083748 180)
		(property "Reference" "R4065"
			(at 0 0 180)
			(layer "F.SilkS")
			(hide yes)
			(effects
				(font
					(size 1.27 1.27)
				)
			)
		)
		(property "Value" ""
			(at 0 0 180)
			(layer "F.Fab")
			(effects
				(font
					(size 1.27 1.27)
				)
			)
		)
		(duplicate_pad_numbers_are_jumpers no)
		(fp_line
			(start 0.7874 0.4064)
			(end -0.7874 0.4064)
			(stroke
				(width 0.1524)
				(type default)
			)
			(layer "F.SilkS")
		)
		(fp_line
			(start 0.7874 -0.4064)
			(end 0.7874 0.4064)
			(stroke
				(width 0.1524)
				(type default)
			)
			(layer "F.SilkS")
		)
		(fp_line
			(start -0.7874 0.4064)
			(end -0.7874 -0.4064)
			(stroke
				(width 0.1524)
				(type default)
			)
			(layer "F.SilkS")
		)
		(fp_line
			(start -0.7874 -0.4064)
			(end 0.7874 -0.4064)
			(stroke
				(width 0.1524)
				(type default)
			)
			(layer "F.SilkS")
		)
		(fp_line
			(start 0.67945 0.3048)
			(end 0.120396 0.3048)
			(stroke
				(width 0.1)
				(type default)
			)
			(layer "F.Fab")
		)
		(fp_line
			(start 0.67945 -0.3048)
			(end 0.67945 0.3048)
			(stroke
				(width 0.1)
				(type default)
			)
			(layer "F.Fab")
		)
		(fp_line
			(start 0.12065 -0.2794)
			(end 0.12065 -0.3048)
			(stroke
				(width 0.1)
				(type default)
			)
			(layer "F.Fab")
		)
		(fp_line
			(start 0.12065 -0.3048)
			(end 0.67945 -0.3048)
			(stroke
				(width 0.1)
				(type default)
			)
			(layer "F.Fab")
		)
		(fp_line
			(start 0.120396 0.3048)
			(end 0.120396 0.2794)
			(stroke
				(width 0.1)
				(type default)
			)
			(layer "F.Fab")
		)
		(fp_line
			(start 0.120396 0.2794)
			(end -0.12065 0.2794)
			(stroke
				(width 0.1)
				(type default)
			)
			(layer "F.Fab")
		)
		(fp_line
			(start -0.12065 0.3048)
			(end -0.67945 0.3048)
			(stroke
				(width 0.1)
				(type default)
			)
			(layer "F.Fab")
		)
		(fp_line
			(start -0.12065 0.2794)
			(end -0.12065 0.3048)
			(stroke
				(width 0.1)
				(type default)
			)
			(layer "F.Fab")
		)
		(fp_line
			(start -0.12065 -0.2794)
			(end 0.12065 -0.2794)
			(stroke
				(width 0.1)
				(type default)
			)
			(layer "F.Fab")
		)
		(fp_line
			(start -0.12065 -0.305054)
			(end -0.12065 -0.2794)
			(stroke
				(width 0.1)
				(type default)
			)
			(layer "F.Fab")
		)
		(fp_line
			(start -0.67945 0.3048)
			(end -0.67945 -0.305054)
			(stroke
				(width 0.1)
				(type default)
			)
			(layer "F.Fab")
		)
		(fp_line
			(start -0.67945 -0.305054)
			(end -0.12065 -0.305054)
			(stroke
				(width 0.1)
				(type default)
			)
			(layer "F.Fab")
		)
		(pad "1" smd circle
			(at -0.40005 0 180)
			(size 0 0)
			(layers "F.Cu" "F.Mask" "F.Paste")
			(net "P12V_AUX")
		)
		(pad "2" smd circle
			(at 0.40005 0 180)
			(size 0 0)
			(layers "F.Cu" "F.Mask" "F.Paste")
			(net "P12V_OCP_2_EN_G")
		)
	)
	(footprint ""
		(layer "F.Cu")
		(at 145.501106 -408.517344 -90)
		(property "Reference" "C6714"
			(at 0 0 270)
			(layer "F.SilkS")
			(hide yes)
			(effects
				(font
					(size 1.27 1.27)
				)
			)
		)
		(property "Value" ""
			(at 0 0 270)
			(layer "F.Fab")
			(effects
				(font
					(size 1.27 1.27)
				)
			)
		)
		(duplicate_pad_numbers_are_jumpers no)
		(fp_line
			(start -0.299974 0.150114)
			(end -0.299974 -0.150114)
			(stroke
				(width 0.1)
				(type default)
			)
			(layer "F.Fab")
		)
		(fp_line
			(start 0.299974 0.150114)
			(end -0.299974 0.150114)
			(stroke
				(width 0.1)
				(type default)
			)
			(layer "F.Fab")
		)
		(fp_line
			(start -0.299974 -0.150114)
			(end 0.299974 -0.150114)
			(stroke
				(width 0.1)
				(type default)
			)
			(layer "F.Fab")
		)
		(fp_line
			(start 0.299974 -0.150114)
			(end 0.299974 0.150114)
			(stroke
				(width 0.1)
				(type default)
			)
			(layer "F.Fab")
		)
		(pad "1" smd rect
			(at -0.2667 0 270)
			(size 0.3048 0.381)
			(layers "F.Cu" "F.Mask" "F.Paste")
			(net "P5E_CPU1_P2_TX_BUF_C_DN<10>")
		)
		(pad "2" smd rect
			(at 0.2667 0 270)
			(size 0.3048 0.381)
			(layers "F.Cu" "F.Mask" "F.Paste")
			(net "P5E_CPU1_P2_TX_BUF_DN<10>")
		)
	)
	(footprint ""
		(layer "F.Cu")
		(at 101.770942 -145.377662 -90)
		(property "Reference" "R8180"
			(at 0 0 270)
			(layer "F.SilkS")
			(hide yes)
			(effects
				(font
					(size 1.27 1.27)
				)
			)
		)
		(property "Value" ""
			(at 0 0 270)
			(layer "F.Fab")
			(effects
				(font
					(size 1.27 1.27)
				)
			)
		)
		(duplicate_pad_numbers_are_jumpers no)
		(fp_line
			(start -0.7874 0.4064)
			(end -0.7874 -0.4064)
			(stroke
				(width 0.1524)
				(type default)
			)
			(layer "F.SilkS")
		)
		(fp_line
			(start 0.7874 0.4064)
			(end -0.7874 0.4064)
			(stroke
				(width 0.1524)
				(type default)
			)
			(layer "F.SilkS")
		)
		(fp_line
			(start -0.7874 -0.4064)
			(end 0.7874 -0.4064)
			(stroke
				(width 0.1524)
				(type default)
			)
			(layer "F.SilkS")
		)
		(fp_line
			(start 0.7874 -0.4064)
			(end 0.7874 0.4064)
			(stroke
				(width 0.1524)
				(type default)
			)
			(layer "F.SilkS")
		)
		(fp_line
			(start -0.67945 0.3048)
			(end -0.67945 -0.305054)
			(stroke
				(width 0.1)
				(type default)
			)
			(layer "F.Fab")
		)
		(fp_line
			(start -0.12065 0.3048)
			(end -0.67945 0.3048)
			(stroke
				(width 0.1)
				(type default)
			)
			(layer "F.Fab")
		)
		(fp_line
			(start 0.120396 0.3048)
			(end 0.120396 0.2794)
			(stroke
				(width 0.1)
				(type default)
			)
			(layer "F.Fab")
		)
		(fp_line
			(start 0.67945 0.3048)
			(end 0.120396 0.3048)
			(stroke
				(width 0.1)
				(type default)
			)
			(layer "F.Fab")
		)
		(fp_line
			(start -0.12065 0.2794)
			(end -0.12065 0.3048)
			(stroke
				(width 0.1)
				(type default)
			)
			(layer "F.Fab")
		)
		(fp_line
			(start 0.120396 0.2794)
			(end -0.12065 0.2794)
			(stroke
				(width 0.1)
				(type default)
			)
			(layer "F.Fab")
		)
		(fp_line
			(start -0.12065 -0.2794)
			(end 0.12065 -0.2794)
			(stroke
				(width 0.1)
				(type default)
			)
			(layer "F.Fab")
		)
		(fp_line
			(start 0.12065 -0.2794)
			(end 0.12065 -0.3048)
			(stroke
				(width 0.1)
				(type default)
			)
			(layer "F.Fab")
		)
		(fp_line
			(start 0.12065 -0.3048)
			(end 0.67945 -0.3048)
			(stroke
				(width 0.1)
				(type default)
			)
			(layer "F.Fab")
		)
		(fp_line
			(start 0.67945 -0.3048)
			(end 0.67945 0.3048)
			(stroke
				(width 0.1)
				(type default)
			)
			(layer "F.Fab")
		)
		(fp_line
			(start -0.67945 -0.305054)
			(end -0.12065 -0.305054)
			(stroke
				(width 0.1)
				(type default)
			)
			(layer "F.Fab")
		)
		(fp_line
			(start -0.12065 -0.305054)
			(end -0.12065 -0.2794)
			(stroke
				(width 0.1)
				(type default)
			)
			(layer "F.Fab")
		)
		(pad "1" smd circle
			(at -0.40005 0 270)
			(size 0 0)
			(layers "F.Cu" "F.Mask" "F.Paste")
			(net "PVDD18_S5_P1")
		)
		(pad "2" smd circle
			(at 0.40005 0 270)
			(size 0 0)
			(layers "F.Cu" "F.Mask" "F.Paste")
			(net "PVDDCR_CPU0_P1_OCP_N_R")
		)
	)
)
